FILE_TYPE = MULTI_PHYS_TABLE;

PART 'MEC_NPTH'
CLASS=MECHANICAL

{========================================================================================}
:JEDEC_TYPE                  = JEDEC_TYPE                  ;
{========================================================================================}
 'MTH177C167N'                = 'MTH177C167N'              
 'MTH138C128N'                = 'MTH138C128N'              
 'MTH122C240N'                = 'MTH122C240N'              
 'MTH110C280N'                = 'MTH110C280N'              
 'MTH116C236N'                = 'MTH116C236N'              
 'MTH100C240N'                = 'MTH100C240N'              
 'MTH116C200N'                = 'MTH116C200N'              
 'MTH165C340N'                = 'MTH165C340N'              
 'MTH130C340N'                = 'MTH130C340N'              
 'MTH130C217N'                = 'MTH130C217N'              
 'MTH125C280N'                = 'MTH125C280N'              
 'MTH169C315N'                = 'MTH169C315N'              
 'MTH138C315N'                = 'MTH138C315N'              
 'MTH137C276N'                = 'MTH137C276N'              
 'MTH110C100N'                = 'MTH110C100N'              
 'MTH205C195N'                = 'MTH205C195N'              
 'MTH098C088N'                = 'MTH098C088N'              
 'MTH252C472N'                = 'MTH252C472N'              
 'MTH201CT551CB315N'          = 'MTH201CT551CB315N'        
 'MTH173X197OBT315B650X315N'  = 'MTH173X197OBT315B650X315N'
 'MTH252C402N'                = 'MTH252C402N'              
 'MTH150C236N'                = 'MTH150C236N'              
 'MTH110C236N'                = 'MTH110C236N'              
 'MTH098C197N'                = 'MTH098C197N'              
 'MTH125C197N'                = 'MTH125C197N'              
 'MTH146C136N'                = 'MTH146C136N'              
 'MTH165X189OB155X179N'       = 'MTH165X189OB155X179N'     
 'MTH165C320N'                = 'MTH165C320N'              
 'MTH110C315N'                = 'MTH110C315N'              
 'MTH126C116N'                = 'MTH126C116N'              
 'MTH138CT128OB275X465N'      = 'MTH138CT128OB275X465N'    
 'MTH156C146N'                = 'MTH156C146N'              
 'MTH083C073N'                = 'MTH083C073N'              
 'MTH134CT124CB315N'          = 'MTH134CT124CB315N'        
 'MTH635X390OB625X380N_2N'    = 'MTH635X390OB625X380N_2N'        
 'MTH067C057N'                = 'MTH067C057N'              
 'MTH209C199N'                = 'MTH209C199N'              
 'MTH087C077N'                = 'MTH087C077N'              
 'MTH059X138OB049X128N'       = 'MTH059X138OB049X128N'              

END_PART

END.

